# S9S_MB_2U (Grand Teton) — schematic netlist excerpt (pin names and nets, part order shuffled) for the footprints in the layout excerpt that follows; sources: Cadence DE-HDL packaged netlist, KiCad conversion of 03242023_DA0F0TMBIJ0_F0T_Motherboard_J_brd_V01_OCP.brd

R401  Q_RES  10K 1% EMPTY  pkg 0402LF  page 204 : A = P3V3_AUX ; B = IRQ_TPM_SPI_N

PL28  Q_INDUCTOR4P_14  150NH IND  pkg L_TLM117513Q-151QL_11X7-5XA  page 286
  \1\  = SW_PVCCIN_CPU1_SW4
  \2\  = IND_P1_CPL4
  \3\  = IND_P1_CPL3
  \4\  = PVCCIN_CPU1

(kicad_pcb
	(version 20260206)
	(generator "pcbnew")
	(generator_version "10.0")
	(general
		(thickness 1.6)
		(legacy_teardrops no)
	)
	(paper "A4")
	(title_block
		(title "03242023_DA0F0TMBIJ0_F0T_Motherboard_J_brd_V01_OCP.brd")
		(comment 1 "Grand Teton / footprints 298-299 of 6105")
	)
	(layers
		(0 "F.Cu" signal "TOP")
		(4 "In1.Cu" signal "GND")
		(6 "In2.Cu" signal "IN1")
		(8 "In3.Cu" signal "GND1")
		(10 "In4.Cu" signal "IN2")
		(12 "In5.Cu" signal "GND2")
		(14 "In6.Cu" signal "IN3")
		(16 "In7.Cu" signal "GND3")
		(18 "In8.Cu" signal "VCC")
		(20 "In9.Cu" signal "VCC1")
		(22 "In10.Cu" signal "GND4")
		(24 "In11.Cu" signal "IN4")
		(26 "In12.Cu" signal "GND5")
		(28 "In13.Cu" signal "IN5")
		(30 "In14.Cu" signal "GND6")
		(32 "In15.Cu" signal "IN6")
		(34 "In16.Cu" signal "GND7")
		(2 "B.Cu" signal "BOTTOM")
		(9 "F.Adhes" user "F.Adhesive")
		(11 "B.Adhes" user "B.Adhesive")
		(13 "F.Paste" user "Package Geometry/Pastemask Top")
		(15 "B.Paste" user "Package Geometry/Pastemask Bottom")
		(5 "F.SilkS" user "Ref Des/Silkscreen Top")
		(7 "B.SilkS" user "Ref Des/Silkscreen Bottom")
		(1 "F.Mask" user "Board Geometry/Soldermask Top")
		(3 "B.Mask" user "Board Geometry/Soldermask Bottom")
		(17 "Dwgs.User" user "User.Drawings")
		(19 "Cmts.User" user "User.Comments")
		(21 "Eco1.User" user "User.Eco1")
		(23 "Eco2.User" user "User.Eco2")
		(25 "Edge.Cuts" user "Board Geometry/Outline")
		(27 "Margin" user)
		(31 "F.CrtYd" user "Package Geometry/Place Bound Top")
		(29 "B.CrtYd" user "Package Geometry/Place Bound Bottom")
		(35 "F.Fab" user "Ref Des/Assembly Top")
		(33 "B.Fab" user "Ref Des/Assembly Bottom")
	)
	(footprint ""
		(layer "F.Cu")
		(at 320.190622 -55.235348)
		(property "Reference" "R401"
			(at 0 0 0)
			(layer "F.SilkS")
			(hide yes)
			(effects
				(font
					(size 1.27 1.27)
				)
			)
		)
		(property "Value" ""
			(at 0 0 0)
			(layer "F.Fab")
			(effects
				(font
					(size 1.27 1.27)
				)
			)
		)
		(duplicate_pad_numbers_are_jumpers no)
		(fp_line
			(start -0.7874 -0.4064)
			(end 0.7874 -0.4064)
			(stroke
				(width 0.1524)
				(type default)
			)
			(layer "F.SilkS")
		)
		(fp_line
			(start -0.7874 0.4064)
			(end -0.7874 -0.4064)
			(stroke
				(width 0.1524)
				(type default)
			)
			(layer "F.SilkS")
		)
		(fp_line
			(start 0.7874 -0.4064)
			(end 0.7874 0.4064)
			(stroke
				(width 0.1524)
				(type default)
			)
			(layer "F.SilkS")
		)
		(fp_line
			(start 0.7874 0.4064)
			(end -0.7874 0.4064)
			(stroke
				(width 0.1524)
				(type default)
			)
			(layer "F.SilkS")
		)
		(fp_line
			(start -0.67945 -0.305054)
			(end -0.12065 -0.305054)
			(stroke
				(width 0.1)
				(type default)
			)
			(layer "F.Fab")
		)
		(fp_line
			(start -0.67945 0.3048)
			(end -0.67945 -0.305054)
			(stroke
				(width 0.1)
				(type default)
			)
			(layer "F.Fab")
		)
		(fp_line
			(start -0.12065 -0.305054)
			(end -0.12065 -0.2794)
			(stroke
				(width 0.1)
				(type default)
			)
			(layer "F.Fab")
		)
		(fp_line
			(start -0.12065 -0.2794)
			(end 0.12065 -0.2794)
			(stroke
				(width 0.1)
				(type default)
			)
			(layer "F.Fab")
		)
		(fp_line
			(start -0.12065 0.2794)
			(end -0.12065 0.3048)
			(stroke
				(width 0.1)
				(type default)
			)
			(layer "F.Fab")
		)
		(fp_line
			(start -0.12065 0.3048)
			(end -0.67945 0.3048)
			(stroke
				(width 0.1)
				(type default)
			)
			(layer "F.Fab")
		)
		(fp_line
			(start 0.120396 0.2794)
			(end -0.12065 0.2794)
			(stroke
				(width 0.1)
				(type default)
			)
			(layer "F.Fab")
		)
		(fp_line
			(start 0.120396 0.3048)
			(end 0.120396 0.2794)
			(stroke
				(width 0.1)
				(type default)
			)
			(layer "F.Fab")
		)
		(fp_line
			(start 0.12065 -0.3048)
			(end 0.67945 -0.3048)
			(stroke
				(width 0.1)
				(type default)
			)
			(layer "F.Fab")
		)
		(fp_line
			(start 0.12065 -0.2794)
			(end 0.12065 -0.3048)
			(stroke
				(width 0.1)
				(type default)
			)
			(layer "F.Fab")
		)
		(fp_line
			(start 0.67945 -0.3048)
			(end 0.67945 0.3048)
			(stroke
				(width 0.1)
				(type default)
			)
			(layer "F.Fab")
		)
		(fp_line
			(start 0.67945 0.3048)
			(end 0.120396 0.3048)
			(stroke
				(width 0.1)
				(type default)
			)
			(layer "F.Fab")
		)
		(pad "1" smd circle
			(at -0.40005 0)
			(size 0 0)
			(layers "F.Cu" "F.Mask" "F.Paste")
			(net "P3V3_AUX")
		)
		(pad "2" smd circle
			(at 0.40005 0)
			(size 0 0)
			(layers "F.Cu" "F.Mask" "F.Paste")
			(net "IRQ_TPM_SPI_N")
		)
	)
	(footprint ""
		(layer "F.Cu")
		(at 121.521982 -324.445376)
		(property "Reference" "PL28"
			(at 7.738618 5.508498 0)
			(unlocked yes)
			(layer "F.SilkS")
			(effects
				(font
					(size 0.7874 0.5842)
					(thickness 0.1524)
				)
				(justify left)
			)
		)
		(property "Value" ""
			(at 0 0 0)
			(layer "F.Fab")
			(effects
				(font
					(size 1.27 1.27)
				)
			)
		)
		(duplicate_pad_numbers_are_jumpers no)
		(fp_line
			(start -3.750056 -5.500116)
			(end -2.393442 -5.500116)
			(stroke
				(width 0.1524)
				(type default)
			)
			(layer "F.SilkS")
		)
		(fp_line
			(start -3.750056 5.500116)
			(end -3.750056 -5.500116)
			(stroke
				(width 0.1524)
				(type default)
			)
			(layer "F.SilkS")
		)
		(fp_line
			(start -2.393442 5.500116)
			(end -3.750056 5.500116)
			(stroke
				(width 0.1524)
				(type default)
			)
			(layer "F.SilkS")
		)
		(fp_line
			(start 2.393442 5.500116)
			(end 3.750056 5.500116)
			(stroke
				(width 0.1524)
				(type default)
			)
			(layer "F.SilkS")
		)
		(fp_line
			(start 3.750056 -5.500116)
			(end 2.393442 -5.500116)
			(stroke
				(width 0.1524)
				(type default)
			)
			(layer "F.SilkS")
		)
		(fp_line
			(start 3.750056 5.500116)
			(end 3.750056 -5.500116)
			(stroke
				(width 0.1524)
				(type default)
			)
			(layer "F.SilkS")
		)
		(fp_poly
			(pts
				(xy -3.575304 -7.087362) (xy -3.216148 -6.00964) (xy -4.29387 -6.36905)
			)
			(stroke
				(width 0)
				(type default)
			)
			(fill yes)
			(layer "F.SilkS")
		)
		(fp_line
			(start -3.750056 -5.500116)
			(end -3.750056 5.500116)
			(stroke
				(width 0.1)
				(type default)
			)
			(layer "F.Fab")
		)
		(fp_line
			(start -3.750056 5.500116)
			(end 3.750056 5.500116)
			(stroke
				(width 0.1)
				(type default)
			)
			(layer "F.Fab")
		)
		(fp_line
			(start 3.750056 -5.500116)
			(end -3.750056 -5.500116)
			(stroke
				(width 0.1)
				(type default)
			)
			(layer "F.Fab")
		)
		(fp_line
			(start 3.750056 5.500116)
			(end 3.750056 -5.500116)
			(stroke
				(width 0.1)
				(type default)
			)
			(layer "F.Fab")
		)
		(fp_poly
			(pts
				(xy -4.9276 -4.757928) (xy -4.9276 -3.741928) (xy -3.9116 -4.249928)
			)
			(stroke
				(width 0)
				(type default)
			)
			(fill yes)
			(layer "F.Fab")
		)
		(pad "1" smd rect
			(at 0 -4.249928 270)
			(size 2.413 4.5212)
			(layers "F.Cu" "F.Mask" "F.Paste")
			(net "SW_PVCCIN_CPU1_SW4")
		)
		(pad "2" smd rect
			(at 0 -1.175004 270)
			(size 1.3716 4.5212)
			(layers "F.Cu" "F.Mask" "F.Paste")
			(net "IND_P1_CPL4")
		)
		(pad "3" smd rect
			(at 0 1.175004 270)
			(size 1.3716 4.5212)
			(layers "F.Cu" "F.Mask" "F.Paste")
			(net "IND_P1_CPL3")
		)
		(pad "4" smd rect
			(at 0 4.249928 270)
			(size 2.413 4.5212)
			(layers "F.Cu" "F.Mask" "F.Paste")
			(net "PVCCIN_CPU1")
		)
	)
)
